FILE_TYPE = MACRO_DRAWING;
SET COLOR_WIRE YELLOW;
SET COLOR_PROP ORANGE;
SET COLOR_DOT WHITE;
SET COLOR_ARC YELLOW;
SET COLOR_BODY GREEN;
SET COLOR_NOTE PURPLE;
SET PROP_DISPLAY VALUE;
SET PAGE_NUMBER P11;
FORCEADD QUANTA_TITLE_BLOCK_C..1
(5900 -1525);
FORCEPROP 1 LAST CUSTOM_TXT_CDS <NAME_2>
J 0
(2725 -1475);
FORCEPROP 1 LAST CUSTOM_TXT_CDS <NAME_1>
J 0
(2725 -1350);
FORCEPROP 1 LAST CUSTOM_TXT_CDS <Q_NUMBER>
J 0
(4497 -1422);
DISPLAY 1.212766 (4497 -1422);
FORCEPROP 1 LAST CUSTOM_TXT_CDS <Q_PROJ>
J 0
(3518 -1423);
DISPLAY 1.212766 (3518 -1423);
FORCEPROP 1 LAST CUSTOM_TXT_CDS <Q_REV>
J 0
(5716 -1422);
DISPLAY 1.212766 (5716 -1422);
FORCEPROP 1 LAST CUSTOM_TXT_CDS <CON_LAST_MODIFIED>
J 0
(4015 -1510);
DISPLAY 0.978723 (4015 -1510);
FORCEPROP 1 LAST CUSTOM_TXT_CDS <CON_PAGE_NUM> OF <CON_TOTAL_PAGES>
J 0
(5454 -1507);
DISPLAY 0.978723 (5454 -1507);
FORCEPROP 1 LAST Q_TITLE BLOCK DIAGRAM - POWER SEQUENCE
J 0
(-3366 -1524);
DISPLAY 2.446809 (-3366 -1524);
PAINT GREEN (-3366 -1524);
FORCEPROP 1 LAST Q_DEPT 
J 1
(2137 -1476);
DISPLAY 1.957447 (2137 -1476);
PAINT GREEN (2137 -1476);
FORCEPROP 2 LAST CDS_LIB pure_quanta
J 0
(5900 -1525);
PAINT MONO (5900 -1525);
DISPLAY INVISIBLE (5900 -1525);
FORCEPROP 1 LAST CDS_LMAN_SYM_OUTLINE -9475,6775,100,-125
J 0
(5900 -1525);
DISPLAY 0.468085 (5900 -1525);
PAINT GREEN (5900 -1525);
DISPLAY INVISIBLE (5900 -1525);
FORCEPROP 1 LAST COMMENT_BODY TRUE
J 0
(5912 -1538);
DISPLAY 0.978723 (5912 -1538);
PAINT GREEN (5912 -1538);
DISPLAY INVISIBLE (5912 -1538);
FORCEPROP 2 LAST PAGE_BORDER TRUE
J 0
(-1990 3725);
DISPLAY 0.638298 (-1990 3725);
PAINT PINK (-1990 3725);
DISPLAY INVISIBLE (-1990 3725);
FORCEPROP 2 LAST CDS_XR_PAGE_TITLE CR-12 : @S9S_MB_2U_LIB.S9S_MB_2U(SCH_1):PAGE12
J 0
(-1990 3725);
DISPLAY 0.638298 (-1990 3725);
PAINT PINK (-1990 3725);
DISPLAY INVISIBLE (-1990 3725);
FORCEPROP 2 LAST CUSTOM_TXT_CDS <XR_PAGE_TITLE>
J 0
(-1990 3725);
DISPLAY 0.638298 (-1990 3725);
PAINT PINK (-1990 3725);
DISPLAY INVISIBLE (-1990 3725);
FORCEPROP 0 LAST CDS_CON_LAST_MODIFIED Thu Aug 24 16:12:02 2023
J 0
(4015 -1510);
PAINT MONO (4015 -1510);
DISPLAY INVISIBLE (4015 -1510);
FORCENOTE
$CDS_IMAGE|F0T_Power_on_sequrnce_20210928_rev2.jpg|6811|6019
(1300 1925) 0;
DISPLAY LEFT (1300 1925);
QUIT
